FILE_TYPE = MACRO_DRAWING;
SET COLOR_WIRE YELLOW;
SET COLOR_PROP ORANGE;
SET COLOR_DOT WHITE;
SET COLOR_ARC YELLOW;
SET COLOR_BODY GREEN;
SET COLOR_NOTE PURPLE;
SET PROP_DISPLAY VALUE;
SET PAGE_NUMBER P298;
FORCEADD QUANTA_TITLE_BLOCK_C..1
(6275 -1800);
FORCEPROP 1 LAST Q_TITLE BLANK
J 0
(-2975 -1750);
DISPLAY 2.446809 (-2975 -1750);
PAINT GREEN (-2975 -1750);
FORCEPROP 2 LAST CUSTOM_TXT_CDS <Q_REV>
J 0
(6091 -1697);
DISPLAY 1.212766 (6091 -1697);
FORCEPROP 2 LAST CUSTOM_TXT_CDS <CON_PAGE_NUM> OF <CON_TOTAL_PAGES>
J 0
(5829 -1782);
DISPLAY 0.978723 (5829 -1782);
FORCEPROP 2 LAST CUSTOM_TXT_CDS <Q_NUMBER>
J 0
(4872 -1697);
DISPLAY 1.212766 (4872 -1697);
FORCEPROP 2 LAST CUSTOM_TXT_CDS <Q_PROJ>
J 0
(3893 -1698);
DISPLAY 1.212766 (3893 -1698);
FORCEPROP 2 LAST CUSTOM_TXT_CDS <NAME_1>
J 0
(3100 -1625);
FORCEPROP 2 LAST CUSTOM_TXT_CDS <NAME_2>
J 0
(3100 -1750);
FORCEPROP 2 LAST CUSTOM_TXT_CDS <CON_LAST_MODIFIED>
J 0
(4390 -1785);
DISPLAY 0.978723 (4390 -1785);
FORCEPROP 1 LAST Q_DEPT 
J 1
(2512 -1751);
DISPLAY 1.957447 (2512 -1751);
PAINT GREEN (2512 -1751);
FORCEPROP 2 LAST CDS_XR_PAGE_TITLE CR-168 : @S9S_MB_2U_LIB.S9S_MB_2U(SCH_1):PAGE168
J 0
(-1615 3450);
DISPLAY 0.638298 (-1615 3450);
PAINT PINK (-1615 3450);
DISPLAY INVISIBLE (-1615 3450);
FORCEPROP 2 LAST PAGE_BORDER TRUE
J 0
(-1615 3450);
DISPLAY 0.638298 (-1615 3450);
PAINT PINK (-1615 3450);
DISPLAY INVISIBLE (-1615 3450);
FORCEPROP 1 LAST CDS_LMAN_SYM_OUTLINE -9475,6775,100,-125
J 0
(6275 -1800);
DISPLAY 0.468085 (6275 -1800);
PAINT GREEN (6275 -1800);
DISPLAY INVISIBLE (6275 -1800);
FORCEPROP 2 LAST CDS_LIB pure_quanta
J 0
(6275 -1800);
PAINT MONO (6275 -1800);
DISPLAY INVISIBLE (6275 -1800);
FORCEPROP 1 LAST COMMENT_BODY TRUE
J 0
(6287 -1813);
DISPLAY 0.978723 (6287 -1813);
PAINT GREEN (6287 -1813);
DISPLAY INVISIBLE (6287 -1813);
FORCEPROP 2 LAST CUSTOM_TXT_CDS <XR_PAGE_TITLE>
J 0
(-1615 3450);
DISPLAY 0.638298 (-1615 3450);
PAINT PINK (-1615 3450);
DISPLAY INVISIBLE (-1615 3450);
FORCEPROP 0 LAST CDS_CON_LAST_MODIFIED Thu Aug 24 16:14:28 2023
J 0
(4390 -1785);
PAINT MONO (4390 -1785);
DISPLAY INVISIBLE (4390 -1785);
QUIT
